FILE_TYPE = MACRO_DRAWING;
SET COLOR_WIRE YELLOW;
SET COLOR_PROP ORANGE;
SET COLOR_DOT WHITE;
SET COLOR_ARC YELLOW;
SET COLOR_BODY GREEN;
SET COLOR_NOTE PURPLE;
SET PROP_DISPLAY VALUE;
SET PAGE_NUMBER P428;
FORCEADD PT5161LRS..1
(-7700 3775);
FORCEPROP 1 LAST LOCATION U6013
J 0
(-8050 5400);
DISPLAY 0.723404 (-8050 5400);
PAINT GREEN (-8050 5400);
FORCEPROP 0 LAST $SEC 1
J 0
(-8050 5550);
DISPLAY 0.680851 (-8050 5550);
PAINT MONO (-8050 5550);
DISPLAY INVISIBLE (-8050 5550);
FORCEPROP 0 LAST CDS_SEC 1
J 0
(-8050 5550);
DISPLAY 0.680851 (-8050 5550);
DISPLAY INVISIBLE (-8050 5550);
FORCEPROP 0 LASTPIN (-7250 4925) $PN N2
J 0
(-7240 4935);
DISPLAY 0.680851 (-7240 4935);
PAINT MONO (-7240 4935);
FORCEPROP 0 LASTPIN (-7250 4575) $PN Y2
J 0
(-7240 4585);
DISPLAY 0.680851 (-7240 4585);
PAINT MONO (-7240 4585);
FORCEPROP 0 LASTPIN (-7250 4225) $PN AG2
J 0
(-7240 4235);
DISPLAY 0.680851 (-7240 4235);
PAINT MONO (-7240 4235);
FORCEPROP 0 LASTPIN (-7250 3875) $PN AP2
J 0
(-7240 3885);
DISPLAY 0.680851 (-7240 3885);
PAINT MONO (-7240 3885);
FORCEPROP 0 LASTPIN (-7250 3525) $PN BA2
J 0
(-7240 3535);
DISPLAY 0.680851 (-7240 3535);
PAINT MONO (-7240 3535);
FORCEPROP 0 LASTPIN (-7250 3175) $PN BH2
J 0
(-7240 3185);
DISPLAY 0.680851 (-7240 3185);
PAINT MONO (-7240 3185);
FORCEPROP 0 LASTPIN (-7250 2825) $PN BR2
J 0
(-7240 2835);
DISPLAY 0.680851 (-7240 2835);
PAINT MONO (-7240 2835);
FORCEPROP 0 LASTPIN (-7250 2475) $PN CB2
J 0
(-7240 2485);
DISPLAY 0.680851 (-7240 2485);
PAINT MONO (-7240 2485);
FORCEPROP 0 LASTPIN (-7250 5025) $PN R1
J 0
(-7240 5035);
DISPLAY 0.680851 (-7240 5035);
PAINT MONO (-7240 5035);
FORCEPROP 0 LASTPIN (-7250 4675) $PN AB1
J 0
(-7240 4685);
DISPLAY 0.680851 (-7240 4685);
PAINT MONO (-7240 4685);
FORCEPROP 0 LASTPIN (-7250 4325) $PN AJ1
J 0
(-7240 4335);
DISPLAY 0.680851 (-7240 4335);
PAINT MONO (-7240 4335);
FORCEPROP 0 LASTPIN (-7250 3975) $PN AT1
J 0
(-7240 3985);
DISPLAY 0.680851 (-7240 3985);
PAINT MONO (-7240 3985);
FORCEPROP 0 LASTPIN (-7250 3625) $PN BC1
J 0
(-7240 3635);
DISPLAY 0.680851 (-7240 3635);
PAINT MONO (-7240 3635);
FORCEPROP 0 LASTPIN (-7250 3275) $PN BK1
J 0
(-7240 3285);
DISPLAY 0.680851 (-7240 3285);
PAINT MONO (-7240 3285);
FORCEPROP 0 LASTPIN (-7250 2925) $PN BU1
J 0
(-7240 2935);
DISPLAY 0.680851 (-7240 2935);
PAINT MONO (-7240 2935);
FORCEPROP 0 LASTPIN (-7250 2575) $PN CD1
J 0
(-7240 2585);
DISPLAY 0.680851 (-7240 2585);
PAINT MONO (-7240 2585);
FORCEPROP 2 LAST PART_TYPE SMLF
J 0
(-8050 5500);
DISPLAY 0.680851 (-8050 5500);
FORCEPROP 1 LAST MATERIAL IC
J 0
(-8050 5250);
DISPLAY 0.723404 (-8050 5250);
PAINT GREEN (-8050 5250);
FORCEPROP 2 LAST VALUE PT5161LRS
J 0
(-8050 5450);
DISPLAY 0.680851 (-8050 5450);
FORCEPROP 2 LAST CDS_LIB pure_quanta
J 0
(-7700 3775);
DISPLAY INVISIBLE (-7700 3775);
FORCEPROP 1 LAST CDS_LMAN_SYM_OUTLINE -350,1450,300,-1400
J 0
(-7700 3775);
DISPLAY 0.468085 (-7700 3775);
PAINT GREEN (-7700 3775);
DISPLAY INVISIBLE (-7700 3775);
FORCEPROP 1 LAST NEEDS_NO_SIZE TRUE
J 0
(-7700 3775);
DISPLAY 0.723404 (-7700 3775);
PAINT GREEN (-7700 3775);
DISPLAY INVISIBLE (-7700 3775);
FORCEPROP 1 LAST PATH I1
J 0
(-7700 3775);
DISPLAY 0.723404 (-7700 3775);
PAINT GREEN (-7700 3775);
DISPLAY INVISIBLE (-7700 3775);
FORCEPROP 1 LAST PART_NUMBER AJ051610U03
J 0
(-8050 5325);
DISPLAY 0.723404 (-8050 5325);
PAINT GREEN (-8050 5325);
DISPLAY INVISIBLE (-8050 5325);
FORCEADD TAP..1
(-6675 3975);
FORCEPROP 3 LASTPIN (-6725 3975) SIG_NAME P5E_CPU0_P3_RX_BUF_DP<12>
J 0
(-6715 3985);
DISPLAY 0.659574 (-6715 3985);
PAINT MONO (-6715 3985);
DISPLAY INVISIBLE (-6715 3985);
FORCEPROP 1 LASTPIN (-6725 3975) BN 12
J 0
(-6737 3983);
DISPLAY 0.680851 (-6737 3983);
PAINT GREEN (-6737 3983);
FORCEPROP 2 LAST CDS_LIB standard
J 0
(-6675 3975);
DISPLAY INVISIBLE (-6675 3975);
FORCEPROP 1 LAST BODY_TYPE PLUMBING
J 0
(-6675 4025);
DISPLAY 0.872340 (-6675 4025);
PAINT GREEN (-6675 4025);
DISPLAY INVISIBLE (-6675 4025);
FORCEPROP 1 LAST HDL_TAP TRUE
J 0
(-6350 3850);
DISPLAY 0.872340 (-6350 3850);
DISPLAY INVISIBLE (-6350 3850);
FORCEPROP 1 LAST PATH I10
J 0
(-6677 3975);
DISPLAY 0.872340 (-6677 3975);
PAINT GREEN (-6677 3975);
DISPLAY INVISIBLE (-6677 3975);
FORCEADD TAP..1
(-6475 3875);
FORCEPROP 3 LASTPIN (-6525 3875) SIG_NAME P5E_CPU0_P3_RX_BUF_DN<12>
J 0
(-6515 3885);
DISPLAY 0.659574 (-6515 3885);
PAINT MONO (-6515 3885);
DISPLAY INVISIBLE (-6515 3885);
FORCEPROP 1 LASTPIN (-6525 3875) BN 12
J 0
(-6537 3883);
DISPLAY 0.680851 (-6537 3883);
PAINT GREEN (-6537 3883);
FORCEPROP 2 LAST CDS_LIB standard
J 0
(-6475 3875);
DISPLAY INVISIBLE (-6475 3875);
FORCEPROP 1 LAST BODY_TYPE PLUMBING
J 0
(-6475 3925);
DISPLAY 0.872340 (-6475 3925);
PAINT GREEN (-6475 3925);
DISPLAY INVISIBLE (-6475 3925);
FORCEPROP 1 LAST HDL_TAP TRUE
J 0
(-6150 3750);
DISPLAY 0.872340 (-6150 3750);
DISPLAY INVISIBLE (-6150 3750);
FORCEPROP 1 LAST PATH I11
J 0
(-6477 3875);
DISPLAY 0.872340 (-6477 3875);
PAINT GREEN (-6477 3875);
DISPLAY INVISIBLE (-6477 3875);
FORCEADD TAP..1
(-6675 4325);
FORCEPROP 3 LASTPIN (-6725 4325) SIG_NAME P5E_CPU0_P3_RX_BUF_DP<13>
J 0
(-6715 4335);
DISPLAY 0.659574 (-6715 4335);
PAINT MONO (-6715 4335);
DISPLAY INVISIBLE (-6715 4335);
FORCEPROP 1 LASTPIN (-6725 4325) BN 13
J 0
(-6737 4333);
DISPLAY 0.680851 (-6737 4333);
PAINT GREEN (-6737 4333);
FORCEPROP 2 LAST CDS_LIB standard
J 0
(-6675 4325);
DISPLAY INVISIBLE (-6675 4325);
FORCEPROP 1 LAST BODY_TYPE PLUMBING
J 0
(-6675 4375);
DISPLAY 0.872340 (-6675 4375);
PAINT GREEN (-6675 4375);
DISPLAY INVISIBLE (-6675 4375);
FORCEPROP 1 LAST HDL_TAP TRUE
J 0
(-6350 4200);
DISPLAY 0.872340 (-6350 4200);
DISPLAY INVISIBLE (-6350 4200);
FORCEPROP 1 LAST PATH I12
J 0
(-6677 4325);
DISPLAY 0.872340 (-6677 4325);
PAINT GREEN (-6677 4325);
DISPLAY INVISIBLE (-6677 4325);
FORCEADD TAP..1
(-6475 4225);
FORCEPROP 3 LASTPIN (-6525 4225) SIG_NAME P5E_CPU0_P3_RX_BUF_DN<13>
J 0
(-6515 4235);
DISPLAY 0.659574 (-6515 4235);
PAINT MONO (-6515 4235);
DISPLAY INVISIBLE (-6515 4235);
FORCEPROP 1 LASTPIN (-6525 4225) BN 13
J 0
(-6537 4233);
DISPLAY 0.680851 (-6537 4233);
PAINT GREEN (-6537 4233);
FORCEPROP 2 LAST CDS_LIB standard
J 0
(-6475 4225);
DISPLAY INVISIBLE (-6475 4225);
FORCEPROP 1 LAST BODY_TYPE PLUMBING
J 0
(-6475 4275);
DISPLAY 0.872340 (-6475 4275);
PAINT GREEN (-6475 4275);
DISPLAY INVISIBLE (-6475 4275);
FORCEPROP 1 LAST HDL_TAP TRUE
J 0
(-6150 4100);
DISPLAY 0.872340 (-6150 4100);
DISPLAY INVISIBLE (-6150 4100);
FORCEPROP 1 LAST PATH I13
J 0
(-6477 4225);
DISPLAY 0.872340 (-6477 4225);
PAINT GREEN (-6477 4225);
DISPLAY INVISIBLE (-6477 4225);
FORCEADD TAP..1
(-6475 4575);
FORCEPROP 3 LASTPIN (-6525 4575) SIG_NAME P5E_CPU0_P3_RX_BUF_DN<14>
J 0
(-6515 4585);
DISPLAY 0.659574 (-6515 4585);
PAINT MONO (-6515 4585);
DISPLAY INVISIBLE (-6515 4585);
FORCEPROP 1 LASTPIN (-6525 4575) BN 14
J 0
(-6537 4583);
DISPLAY 0.680851 (-6537 4583);
PAINT GREEN (-6537 4583);
FORCEPROP 2 LAST CDS_LIB standard
J 0
(-6475 4575);
DISPLAY INVISIBLE (-6475 4575);
FORCEPROP 1 LAST BODY_TYPE PLUMBING
J 0
(-6475 4625);
DISPLAY 0.872340 (-6475 4625);
PAINT GREEN (-6475 4625);
DISPLAY INVISIBLE (-6475 4625);
FORCEPROP 1 LAST HDL_TAP TRUE
J 0
(-6150 4450);
DISPLAY 0.872340 (-6150 4450);
DISPLAY INVISIBLE (-6150 4450);
FORCEPROP 1 LAST PATH I14
J 0
(-6477 4575);
DISPLAY 0.872340 (-6477 4575);
PAINT GREEN (-6477 4575);
DISPLAY INVISIBLE (-6477 4575);
FORCEADD TAP..1
(-6675 4675);
FORCEPROP 3 LASTPIN (-6725 4675) SIG_NAME P5E_CPU0_P3_RX_BUF_DP<14>
J 0
(-6715 4685);
DISPLAY 0.659574 (-6715 4685);
PAINT MONO (-6715 4685);
DISPLAY INVISIBLE (-6715 4685);
FORCEPROP 1 LASTPIN (-6725 4675) BN 14
J 0
(-6737 4683);
DISPLAY 0.680851 (-6737 4683);
PAINT GREEN (-6737 4683);
FORCEPROP 2 LAST CDS_LIB standard
J 0
(-6675 4675);
DISPLAY INVISIBLE (-6675 4675);
FORCEPROP 1 LAST BODY_TYPE PLUMBING
J 0
(-6675 4725);
DISPLAY 0.872340 (-6675 4725);
PAINT GREEN (-6675 4725);
DISPLAY INVISIBLE (-6675 4725);
FORCEPROP 1 LAST HDL_TAP TRUE
J 0
(-6350 4550);
DISPLAY 0.872340 (-6350 4550);
DISPLAY INVISIBLE (-6350 4550);
FORCEPROP 1 LAST PATH I15
J 0
(-6677 4675);
DISPLAY 0.872340 (-6677 4675);
PAINT GREEN (-6677 4675);
DISPLAY INVISIBLE (-6677 4675);
FORCEADD TAP..1
(-6675 5025);
FORCEPROP 3 LASTPIN (-6725 5025) SIG_NAME P5E_CPU0_P3_RX_BUF_DP<15>
J 0
(-6715 5035);
DISPLAY 0.659574 (-6715 5035);
PAINT MONO (-6715 5035);
DISPLAY INVISIBLE (-6715 5035);
FORCEPROP 1 LASTPIN (-6725 5025) BN 15
J 0
(-6737 5033);
DISPLAY 0.680851 (-6737 5033);
PAINT GREEN (-6737 5033);
FORCEPROP 2 LAST CDS_LIB standard
J 0
(-6675 5025);
DISPLAY INVISIBLE (-6675 5025);
FORCEPROP 1 LAST BODY_TYPE PLUMBING
J 0
(-6675 5075);
DISPLAY 0.872340 (-6675 5075);
PAINT GREEN (-6675 5075);
DISPLAY INVISIBLE (-6675 5075);
FORCEPROP 1 LAST HDL_TAP TRUE
J 0
(-6350 4900);
DISPLAY 0.872340 (-6350 4900);
DISPLAY INVISIBLE (-6350 4900);
FORCEPROP 1 LAST PATH I16
J 0
(-6677 5025);
DISPLAY 0.872340 (-6677 5025);
PAINT GREEN (-6677 5025);
DISPLAY INVISIBLE (-6677 5025);
FORCEADD TAP..1
(-6475 4925);
FORCEPROP 3 LASTPIN (-6525 4925) SIG_NAME P5E_CPU0_P3_RX_BUF_DN<15>
J 0
(-6515 4935);
DISPLAY 0.659574 (-6515 4935);
PAINT MONO (-6515 4935);
DISPLAY INVISIBLE (-6515 4935);
FORCEPROP 1 LASTPIN (-6525 4925) BN 15
J 0
(-6537 4933);
DISPLAY 0.680851 (-6537 4933);
PAINT GREEN (-6537 4933);
FORCEPROP 2 LAST CDS_LIB standard
J 0
(-6475 4925);
DISPLAY INVISIBLE (-6475 4925);
FORCEPROP 1 LAST BODY_TYPE PLUMBING
J 0
(-6475 4975);
DISPLAY 0.872340 (-6475 4975);
PAINT GREEN (-6475 4975);
DISPLAY INVISIBLE (-6475 4975);
FORCEPROP 1 LAST HDL_TAP TRUE
J 0
(-6150 4800);
DISPLAY 0.872340 (-6150 4800);
DISPLAY INVISIBLE (-6150 4800);
FORCEPROP 1 LAST PATH I17
J 0
(-6477 4925);
DISPLAY 0.872340 (-6477 4925);
PAINT GREEN (-6477 4925);
DISPLAY INVISIBLE (-6477 4925);
FORCEADD OFFPAGE..1
R 2
(-5450 5050);
FORCEPROP 2 LAST $XR0 115 
J 0
(-5264 5050);
DISPLAY 0.638298 (-5264 5050);
PAINT MONO (-5264 5050);
FORCEPROP 2 LAST CDS_LIB standard
J 0
(-5450 5050);
DISPLAY INVISIBLE (-5450 5050);
FORCEPROP 1 LAST OFFPAGE TRUE
J 2
(-5775 4925);
DISPLAY 0.872340 (-5775 4925);
DISPLAY INVISIBLE (-5775 4925);
FORCEPROP 1 LAST COMMENT_BODY TRUE
J 2
(-5575 4950);
DISPLAY 0.872340 (-5575 4950);
PAINT GREEN (-5575 4950);
DISPLAY INVISIBLE (-5575 4950);
FORCEPROP 2 LAST PATH I18
J 0
(-5275 5125);
DISPLAY 0.680851 (-5275 5125);
DISPLAY INVISIBLE (-5275 5125);
FORCEADD OFFPAGE..1
R 2
(-5450 5125);
FORCEPROP 2 LAST $XR0 115 
J 0
(-5264 5125);
DISPLAY 0.638298 (-5264 5125);
PAINT MONO (-5264 5125);
FORCEPROP 2 LAST CDS_LIB standard
J 0
(-5450 5125);
DISPLAY INVISIBLE (-5450 5125);
FORCEPROP 1 LAST OFFPAGE TRUE
J 2
(-5775 5000);
DISPLAY 0.872340 (-5775 5000);
DISPLAY INVISIBLE (-5775 5000);
FORCEPROP 1 LAST COMMENT_BODY TRUE
J 2
(-5575 5025);
DISPLAY 0.872340 (-5575 5025);
PAINT GREEN (-5575 5025);
DISPLAY INVISIBLE (-5575 5025);
FORCEPROP 2 LAST PATH I19
J 0
(-5275 5200);
DISPLAY 0.680851 (-5275 5200);
DISPLAY INVISIBLE (-5275 5200);
FORCEADD TAP..1
(-6475 2475);
FORCEPROP 3 LASTPIN (-6525 2475) SIG_NAME P5E_CPU0_P3_RX_BUF_DN<8>
J 0
(-6515 2485);
DISPLAY 0.659574 (-6515 2485);
PAINT MONO (-6515 2485);
DISPLAY INVISIBLE (-6515 2485);
FORCEPROP 1 LASTPIN (-6525 2475) BN 8
J 0
(-6537 2483);
DISPLAY 0.680851 (-6537 2483);
PAINT GREEN (-6537 2483);
FORCEPROP 2 LAST CDS_LIB standard
J 0
(-6475 2475);
DISPLAY INVISIBLE (-6475 2475);
FORCEPROP 1 LAST BODY_TYPE PLUMBING
J 0
(-6475 2525);
DISPLAY 0.872340 (-6475 2525);
PAINT GREEN (-6475 2525);
DISPLAY INVISIBLE (-6475 2525);
FORCEPROP 1 LAST HDL_TAP TRUE
J 0
(-6150 2350);
DISPLAY 0.872340 (-6150 2350);
DISPLAY INVISIBLE (-6150 2350);
FORCEPROP 1 LAST PATH I2
J 0
(-6477 2475);
DISPLAY 0.872340 (-6477 2475);
PAINT GREEN (-6477 2475);
DISPLAY INVISIBLE (-6477 2475);
FORCEADD TAP..1
(-2225 2600);
FORCEPROP 3 LASTPIN (-2275 2600) SIG_NAME P5E_CPU0_P3_RX_BUF_DP<0>
J 0
(-2265 2610);
DISPLAY 0.659574 (-2265 2610);
PAINT MONO (-2265 2610);
DISPLAY INVISIBLE (-2265 2610);
FORCEPROP 1 LASTPIN (-2275 2600) BN 0
J 0
(-2287 2608);
DISPLAY 0.680851 (-2287 2608);
PAINT GREEN (-2287 2608);
FORCEPROP 2 LAST CDS_LIB standard
J 0
(-2225 2600);
DISPLAY INVISIBLE (-2225 2600);
FORCEPROP 1 LAST BODY_TYPE PLUMBING
J 0
(-2225 2650);
DISPLAY 0.872340 (-2225 2650);
PAINT GREEN (-2225 2650);
DISPLAY INVISIBLE (-2225 2650);
FORCEPROP 1 LAST HDL_TAP TRUE
J 0
(-1900 2475);
DISPLAY 0.872340 (-1900 2475);
DISPLAY INVISIBLE (-1900 2475);
FORCEPROP 1 LAST PATH I20
J 0
(-2227 2600);
DISPLAY 0.872340 (-2227 2600);
PAINT GREEN (-2227 2600);
DISPLAY INVISIBLE (-2227 2600);
FORCEADD TAP..1
(-2225 2950);
FORCEPROP 3 LASTPIN (-2275 2950) SIG_NAME P5E_CPU0_P3_RX_BUF_DP<1>
J 0
(-2265 2960);
DISPLAY 0.659574 (-2265 2960);
PAINT MONO (-2265 2960);
DISPLAY INVISIBLE (-2265 2960);
FORCEPROP 1 LASTPIN (-2275 2950) BN 1
J 0
(-2287 2958);
DISPLAY 0.680851 (-2287 2958);
PAINT GREEN (-2287 2958);
FORCEPROP 2 LAST CDS_LIB standard
J 0
(-2225 2950);
DISPLAY INVISIBLE (-2225 2950);
FORCEPROP 1 LAST BODY_TYPE PLUMBING
J 0
(-2225 3000);
DISPLAY 0.872340 (-2225 3000);
PAINT GREEN (-2225 3000);
DISPLAY INVISIBLE (-2225 3000);
FORCEPROP 1 LAST HDL_TAP TRUE
J 0
(-1900 2825);
DISPLAY 0.872340 (-1900 2825);
DISPLAY INVISIBLE (-1900 2825);
FORCEPROP 1 LAST PATH I21
J 0
(-2227 2950);
DISPLAY 0.872340 (-2227 2950);
PAINT GREEN (-2227 2950);
DISPLAY INVISIBLE (-2227 2950);
FORCEADD TAP..1
(-2225 3300);
FORCEPROP 3 LASTPIN (-2275 3300) SIG_NAME P5E_CPU0_P3_RX_BUF_DP<2>
J 0
(-2265 3310);
DISPLAY 0.659574 (-2265 3310);
PAINT MONO (-2265 3310);
DISPLAY INVISIBLE (-2265 3310);
FORCEPROP 1 LASTPIN (-2275 3300) BN 2
J 0
(-2287 3308);
DISPLAY 0.680851 (-2287 3308);
PAINT GREEN (-2287 3308);
FORCEPROP 2 LAST CDS_LIB standard
J 0
(-2225 3300);
DISPLAY INVISIBLE (-2225 3300);
FORCEPROP 1 LAST BODY_TYPE PLUMBING
J 0
(-2225 3350);
DISPLAY 0.872340 (-2225 3350);
PAINT GREEN (-2225 3350);
DISPLAY INVISIBLE (-2225 3350);
FORCEPROP 1 LAST HDL_TAP TRUE
J 0
(-1900 3175);
DISPLAY 0.872340 (-1900 3175);
DISPLAY INVISIBLE (-1900 3175);
FORCEPROP 1 LAST PATH I22
J 0
(-2227 3300);
DISPLAY 0.872340 (-2227 3300);
PAINT GREEN (-2227 3300);
DISPLAY INVISIBLE (-2227 3300);
FORCEADD TAP..1
(-2225 3650);
FORCEPROP 3 LASTPIN (-2275 3650) SIG_NAME P5E_CPU0_P3_RX_BUF_DP<3>
J 0
(-2265 3660);
DISPLAY 0.659574 (-2265 3660);
PAINT MONO (-2265 3660);
DISPLAY INVISIBLE (-2265 3660);
FORCEPROP 1 LASTPIN (-2275 3650) BN 3
J 0
(-2287 3658);
DISPLAY 0.680851 (-2287 3658);
PAINT GREEN (-2287 3658);
FORCEPROP 2 LAST CDS_LIB standard
J 0
(-2225 3650);
DISPLAY INVISIBLE (-2225 3650);
FORCEPROP 1 LAST BODY_TYPE PLUMBING
J 0
(-2225 3700);
DISPLAY 0.872340 (-2225 3700);
PAINT GREEN (-2225 3700);
DISPLAY INVISIBLE (-2225 3700);
FORCEPROP 1 LAST HDL_TAP TRUE
J 0
(-1900 3525);
DISPLAY 0.872340 (-1900 3525);
DISPLAY INVISIBLE (-1900 3525);
FORCEPROP 1 LAST PATH I23
J 0
(-2227 3650);
DISPLAY 0.872340 (-2227 3650);
PAINT GREEN (-2227 3650);
DISPLAY INVISIBLE (-2227 3650);
FORCEADD TAP..1
(-2225 4000);
FORCEPROP 3 LASTPIN (-2275 4000) SIG_NAME P5E_CPU0_P3_RX_BUF_DP<4>
J 0
(-2265 4010);
DISPLAY 0.659574 (-2265 4010);
PAINT MONO (-2265 4010);
DISPLAY INVISIBLE (-2265 4010);
FORCEPROP 1 LASTPIN (-2275 4000) BN 4
J 0
(-2287 4008);
DISPLAY 0.680851 (-2287 4008);
PAINT GREEN (-2287 4008);
FORCEPROP 2 LAST CDS_LIB standard
J 0
(-2225 4000);
DISPLAY INVISIBLE (-2225 4000);
FORCEPROP 1 LAST BODY_TYPE PLUMBING
J 0
(-2225 4050);
DISPLAY 0.872340 (-2225 4050);
PAINT GREEN (-2225 4050);
DISPLAY INVISIBLE (-2225 4050);
FORCEPROP 1 LAST HDL_TAP TRUE
J 0
(-1900 3875);
DISPLAY 0.872340 (-1900 3875);
DISPLAY INVISIBLE (-1900 3875);
FORCEPROP 1 LAST PATH I24
J 0
(-2227 4000);
DISPLAY 0.872340 (-2227 4000);
PAINT GREEN (-2227 4000);
DISPLAY INVISIBLE (-2227 4000);
FORCEADD TAP..1
(-2025 2500);
FORCEPROP 3 LASTPIN (-2075 2500) SIG_NAME P5E_CPU0_P3_RX_BUF_DN<0>
J 0
(-2065 2510);
DISPLAY 0.659574 (-2065 2510);
PAINT MONO (-2065 2510);
DISPLAY INVISIBLE (-2065 2510);
FORCEPROP 1 LASTPIN (-2075 2500) BN 0
J 0
(-2087 2508);
DISPLAY 0.680851 (-2087 2508);
PAINT GREEN (-2087 2508);
FORCEPROP 2 LAST CDS_LIB standard
J 0
(-2025 2500);
DISPLAY INVISIBLE (-2025 2500);
FORCEPROP 1 LAST BODY_TYPE PLUMBING
J 0
(-2025 2550);
DISPLAY 0.872340 (-2025 2550);
PAINT GREEN (-2025 2550);
DISPLAY INVISIBLE (-2025 2550);
FORCEPROP 1 LAST HDL_TAP TRUE
J 0
(-1700 2375);
DISPLAY 0.872340 (-1700 2375);
DISPLAY INVISIBLE (-1700 2375);
FORCEPROP 1 LAST PATH I25
J 0
(-2027 2500);
DISPLAY 0.872340 (-2027 2500);
PAINT GREEN (-2027 2500);
DISPLAY INVISIBLE (-2027 2500);
FORCEADD TAP..1
(-2025 2850);
FORCEPROP 3 LASTPIN (-2075 2850) SIG_NAME P5E_CPU0_P3_RX_BUF_DN<1>
J 0
(-2065 2860);
DISPLAY 0.659574 (-2065 2860);
PAINT MONO (-2065 2860);
DISPLAY INVISIBLE (-2065 2860);
FORCEPROP 1 LASTPIN (-2075 2850) BN 1
J 0
(-2087 2858);
DISPLAY 0.680851 (-2087 2858);
PAINT GREEN (-2087 2858);
FORCEPROP 2 LAST CDS_LIB standard
J 0
(-2025 2850);
DISPLAY INVISIBLE (-2025 2850);
FORCEPROP 1 LAST BODY_TYPE PLUMBING
J 0
(-2025 2900);
DISPLAY 0.872340 (-2025 2900);
PAINT GREEN (-2025 2900);
DISPLAY INVISIBLE (-2025 2900);
FORCEPROP 1 LAST HDL_TAP TRUE
J 0
(-1700 2725);
DISPLAY 0.872340 (-1700 2725);
DISPLAY INVISIBLE (-1700 2725);
FORCEPROP 1 LAST PATH I26
J 0
(-2027 2850);
DISPLAY 0.872340 (-2027 2850);
PAINT GREEN (-2027 2850);
DISPLAY INVISIBLE (-2027 2850);
FORCEADD TAP..1
(-2025 3200);
FORCEPROP 3 LASTPIN (-2075 3200) SIG_NAME P5E_CPU0_P3_RX_BUF_DN<2>
J 0
(-2065 3210);
DISPLAY 0.659574 (-2065 3210);
PAINT MONO (-2065 3210);
DISPLAY INVISIBLE (-2065 3210);
FORCEPROP 1 LASTPIN (-2075 3200) BN 2
J 0
(-2087 3208);
DISPLAY 0.680851 (-2087 3208);
PAINT GREEN (-2087 3208);
FORCEPROP 2 LAST CDS_LIB standard
J 0
(-2025 3200);
DISPLAY INVISIBLE (-2025 3200);
FORCEPROP 1 LAST BODY_TYPE PLUMBING
J 0
(-2025 3250);
DISPLAY 0.872340 (-2025 3250);
PAINT GREEN (-2025 3250);
DISPLAY INVISIBLE (-2025 3250);
FORCEPROP 1 LAST HDL_TAP TRUE
J 0
(-1700 3075);
DISPLAY 0.872340 (-1700 3075);
DISPLAY INVISIBLE (-1700 3075);
FORCEPROP 1 LAST PATH I27
J 0
(-2027 3200);
DISPLAY 0.872340 (-2027 3200);
PAINT GREEN (-2027 3200);
DISPLAY INVISIBLE (-2027 3200);
FORCEADD TAP..1
(-2025 3550);
FORCEPROP 3 LASTPIN (-2075 3550) SIG_NAME P5E_CPU0_P3_RX_BUF_DN<3>
J 0
(-2065 3560);
DISPLAY 0.659574 (-2065 3560);
PAINT MONO (-2065 3560);
DISPLAY INVISIBLE (-2065 3560);
FORCEPROP 1 LASTPIN (-2075 3550) BN 3
J 0
(-2087 3558);
DISPLAY 0.680851 (-2087 3558);
PAINT GREEN (-2087 3558);
FORCEPROP 2 LAST CDS_LIB standard
J 0
(-2025 3550);
DISPLAY INVISIBLE (-2025 3550);
FORCEPROP 1 LAST BODY_TYPE PLUMBING
J 0
(-2025 3600);
DISPLAY 0.872340 (-2025 3600);
PAINT GREEN (-2025 3600);
DISPLAY INVISIBLE (-2025 3600);
FORCEPROP 1 LAST HDL_TAP TRUE
J 0
(-1700 3425);
DISPLAY 0.872340 (-1700 3425);
DISPLAY INVISIBLE (-1700 3425);
FORCEPROP 1 LAST PATH I28
J 0
(-2027 3550);
DISPLAY 0.872340 (-2027 3550);
PAINT GREEN (-2027 3550);
DISPLAY INVISIBLE (-2027 3550);
FORCEADD TAP..1
(-2025 3900);
FORCEPROP 3 LASTPIN (-2075 3900) SIG_NAME P5E_CPU0_P3_RX_BUF_DN<4>
J 0
(-2065 3910);
DISPLAY 0.659574 (-2065 3910);
PAINT MONO (-2065 3910);
DISPLAY INVISIBLE (-2065 3910);
FORCEPROP 1 LASTPIN (-2075 3900) BN 4
J 0
(-2087 3908);
DISPLAY 0.680851 (-2087 3908);
PAINT GREEN (-2087 3908);
FORCEPROP 2 LAST CDS_LIB standard
J 0
(-2025 3900);
DISPLAY INVISIBLE (-2025 3900);
FORCEPROP 1 LAST BODY_TYPE PLUMBING
J 0
(-2025 3950);
DISPLAY 0.872340 (-2025 3950);
PAINT GREEN (-2025 3950);
DISPLAY INVISIBLE (-2025 3950);
FORCEPROP 1 LAST HDL_TAP TRUE
J 0
(-1700 3775);
DISPLAY 0.872340 (-1700 3775);
DISPLAY INVISIBLE (-1700 3775);
FORCEPROP 1 LAST PATH I29
J 0
(-2027 3900);
DISPLAY 0.872340 (-2027 3900);
PAINT GREEN (-2027 3900);
DISPLAY INVISIBLE (-2027 3900);
FORCEADD TAP..1
(-6675 2575);
FORCEPROP 3 LASTPIN (-6725 2575) SIG_NAME P5E_CPU0_P3_RX_BUF_DP<8>
J 0
(-6715 2585);
DISPLAY 0.659574 (-6715 2585);
PAINT MONO (-6715 2585);
DISPLAY INVISIBLE (-6715 2585);
FORCEPROP 1 LASTPIN (-6725 2575) BN 8
J 0
(-6737 2583);
DISPLAY 0.680851 (-6737 2583);
PAINT GREEN (-6737 2583);
FORCEPROP 2 LAST CDS_LIB standard
J 0
(-6675 2575);
DISPLAY INVISIBLE (-6675 2575);
FORCEPROP 1 LAST BODY_TYPE PLUMBING
J 0
(-6675 2625);
DISPLAY 0.872340 (-6675 2625);
PAINT GREEN (-6675 2625);
DISPLAY INVISIBLE (-6675 2625);
FORCEPROP 1 LAST HDL_TAP TRUE
J 0
(-6350 2450);
DISPLAY 0.872340 (-6350 2450);
DISPLAY INVISIBLE (-6350 2450);
FORCEPROP 1 LAST PATH I3
J 0
(-6677 2575);
DISPLAY 0.872340 (-6677 2575);
PAINT GREEN (-6677 2575);
DISPLAY INVISIBLE (-6677 2575);
FORCEADD TAP..1
(-2225 4350);
FORCEPROP 3 LASTPIN (-2275 4350) SIG_NAME P5E_CPU0_P3_RX_BUF_DP<5>
J 0
(-2265 4360);
DISPLAY 0.659574 (-2265 4360);
PAINT MONO (-2265 4360);
DISPLAY INVISIBLE (-2265 4360);
FORCEPROP 1 LASTPIN (-2275 4350) BN 5
J 0
(-2287 4358);
DISPLAY 0.680851 (-2287 4358);
PAINT GREEN (-2287 4358);
FORCEPROP 2 LAST CDS_LIB standard
J 0
(-2225 4350);
DISPLAY INVISIBLE (-2225 4350);
FORCEPROP 1 LAST BODY_TYPE PLUMBING
J 0
(-2225 4400);
DISPLAY 0.872340 (-2225 4400);
PAINT GREEN (-2225 4400);
DISPLAY INVISIBLE (-2225 4400);
FORCEPROP 1 LAST HDL_TAP TRUE
J 0
(-1900 4225);
DISPLAY 0.872340 (-1900 4225);
DISPLAY INVISIBLE (-1900 4225);
FORCEPROP 1 LAST PATH I30
J 0
(-2227 4350);
DISPLAY 0.872340 (-2227 4350);
PAINT GREEN (-2227 4350);
DISPLAY INVISIBLE (-2227 4350);
FORCEADD TAP..1
(-2225 4700);
FORCEPROP 3 LASTPIN (-2275 4700) SIG_NAME P5E_CPU0_P3_RX_BUF_DP<6>
J 0
(-2265 4710);
DISPLAY 0.659574 (-2265 4710);
PAINT MONO (-2265 4710);
DISPLAY INVISIBLE (-2265 4710);
FORCEPROP 1 LASTPIN (-2275 4700) BN 6
J 0
(-2287 4708);
DISPLAY 0.680851 (-2287 4708);
PAINT GREEN (-2287 4708);
FORCEPROP 2 LAST CDS_LIB standard
J 0
(-2225 4700);
DISPLAY INVISIBLE (-2225 4700);
FORCEPROP 1 LAST BODY_TYPE PLUMBING
J 0
(-2225 4750);
DISPLAY 0.872340 (-2225 4750);
PAINT GREEN (-2225 4750);
DISPLAY INVISIBLE (-2225 4750);
FORCEPROP 1 LAST HDL_TAP TRUE
J 0
(-1900 4575);
DISPLAY 0.872340 (-1900 4575);
DISPLAY INVISIBLE (-1900 4575);
FORCEPROP 1 LAST PATH I31
J 0
(-2227 4700);
DISPLAY 0.872340 (-2227 4700);
PAINT GREEN (-2227 4700);
DISPLAY INVISIBLE (-2227 4700);
FORCEADD TAP..1
(-2225 5050);
FORCEPROP 3 LASTPIN (-2275 5050) SIG_NAME P5E_CPU0_P3_RX_BUF_DP<7>
J 0
(-2265 5060);
DISPLAY 0.659574 (-2265 5060);
PAINT MONO (-2265 5060);
DISPLAY INVISIBLE (-2265 5060);
FORCEPROP 1 LASTPIN (-2275 5050) BN 7
J 0
(-2287 5058);
DISPLAY 0.680851 (-2287 5058);
PAINT GREEN (-2287 5058);
FORCEPROP 2 LAST CDS_LIB standard
J 0
(-2225 5050);
DISPLAY INVISIBLE (-2225 5050);
FORCEPROP 1 LAST BODY_TYPE PLUMBING
J 0
(-2225 5100);
DISPLAY 0.872340 (-2225 5100);
PAINT GREEN (-2225 5100);
DISPLAY INVISIBLE (-2225 5100);
FORCEPROP 1 LAST HDL_TAP TRUE
J 0
(-1900 4925);
DISPLAY 0.872340 (-1900 4925);
DISPLAY INVISIBLE (-1900 4925);
FORCEPROP 1 LAST PATH I32
J 0
(-2227 5050);
DISPLAY 0.872340 (-2227 5050);
PAINT GREEN (-2227 5050);
DISPLAY INVISIBLE (-2227 5050);
FORCEADD TAP..1
(-2025 4250);
FORCEPROP 3 LASTPIN (-2075 4250) SIG_NAME P5E_CPU0_P3_RX_BUF_DN<5>
J 0
(-2065 4260);
DISPLAY 0.659574 (-2065 4260);
PAINT MONO (-2065 4260);
DISPLAY INVISIBLE (-2065 4260);
FORCEPROP 1 LASTPIN (-2075 4250) BN 5
J 0
(-2087 4258);
DISPLAY 0.680851 (-2087 4258);
PAINT GREEN (-2087 4258);
FORCEPROP 2 LAST CDS_LIB standard
J 0
(-2025 4250);
DISPLAY INVISIBLE (-2025 4250);
FORCEPROP 1 LAST BODY_TYPE PLUMBING
J 0
(-2025 4300);
DISPLAY 0.872340 (-2025 4300);
PAINT GREEN (-2025 4300);
DISPLAY INVISIBLE (-2025 4300);
FORCEPROP 1 LAST HDL_TAP TRUE
J 0
(-1700 4125);
DISPLAY 0.872340 (-1700 4125);
DISPLAY INVISIBLE (-1700 4125);
FORCEPROP 1 LAST PATH I33
J 0
(-2027 4250);
DISPLAY 0.872340 (-2027 4250);
PAINT GREEN (-2027 4250);
DISPLAY INVISIBLE (-2027 4250);
FORCEADD TAP..1
(-2025 4600);
FORCEPROP 3 LASTPIN (-2075 4600) SIG_NAME P5E_CPU0_P3_RX_BUF_DN<6>
J 0
(-2065 4610);
DISPLAY 0.659574 (-2065 4610);
PAINT MONO (-2065 4610);
DISPLAY INVISIBLE (-2065 4610);
FORCEPROP 1 LASTPIN (-2075 4600) BN 6
J 0
(-2087 4608);
DISPLAY 0.680851 (-2087 4608);
PAINT GREEN (-2087 4608);
FORCEPROP 2 LAST CDS_LIB standard
J 0
(-2025 4600);
DISPLAY INVISIBLE (-2025 4600);
FORCEPROP 1 LAST BODY_TYPE PLUMBING
J 0
(-2025 4650);
DISPLAY 0.872340 (-2025 4650);
PAINT GREEN (-2025 4650);
DISPLAY INVISIBLE (-2025 4650);
FORCEPROP 1 LAST HDL_TAP TRUE
J 0
(-1700 4475);
DISPLAY 0.872340 (-1700 4475);
DISPLAY INVISIBLE (-1700 4475);
FORCEPROP 1 LAST PATH I34
J 0
(-2027 4600);
DISPLAY 0.872340 (-2027 4600);
PAINT GREEN (-2027 4600);
DISPLAY INVISIBLE (-2027 4600);
FORCEADD TAP..1
(-2025 4950);
FORCEPROP 3 LASTPIN (-2075 4950) SIG_NAME P5E_CPU0_P3_RX_BUF_DN<7>
J 0
(-2065 4960);
DISPLAY 0.659574 (-2065 4960);
PAINT MONO (-2065 4960);
DISPLAY INVISIBLE (-2065 4960);
FORCEPROP 1 LASTPIN (-2075 4950) BN 7
J 0
(-2087 4958);
DISPLAY 0.680851 (-2087 4958);
PAINT GREEN (-2087 4958);
FORCEPROP 2 LAST CDS_LIB standard
J 0
(-2025 4950);
DISPLAY INVISIBLE (-2025 4950);
FORCEPROP 1 LAST BODY_TYPE PLUMBING
J 0
(-2025 5000);
DISPLAY 0.872340 (-2025 5000);
PAINT GREEN (-2025 5000);
DISPLAY INVISIBLE (-2025 5000);
FORCEPROP 1 LAST HDL_TAP TRUE
J 0
(-1700 4825);
DISPLAY 0.872340 (-1700 4825);
DISPLAY INVISIBLE (-1700 4825);
FORCEPROP 1 LAST PATH I35
J 0
(-2027 4950);
DISPLAY 0.872340 (-2027 4950);
PAINT GREEN (-2027 4950);
DISPLAY INVISIBLE (-2027 4950);
FORCEADD OFFPAGE..1
R 2
(-1000 5075);
FORCEPROP 2 LAST $XR0 116 
J 0
(-814 5075);
DISPLAY 0.638298 (-814 5075);
PAINT MONO (-814 5075);
FORCEPROP 2 LAST CDS_LIB standard
J 0
(-1000 5075);
DISPLAY INVISIBLE (-1000 5075);
FORCEPROP 1 LAST OFFPAGE TRUE
J 2
(-1325 4950);
DISPLAY 0.872340 (-1325 4950);
DISPLAY INVISIBLE (-1325 4950);
FORCEPROP 1 LAST COMMENT_BODY TRUE
J 2
(-1125 4975);
DISPLAY 0.872340 (-1125 4975);
PAINT GREEN (-1125 4975);
DISPLAY INVISIBLE (-1125 4975);
FORCEPROP 2 LAST PATH I36
J 0
(-825 5150);
DISPLAY 0.680851 (-825 5150);
DISPLAY INVISIBLE (-825 5150);
FORCEADD OFFPAGE..1
R 2
(-1000 5150);
FORCEPROP 2 LAST $XR0 116 
J 0
(-814 5150);
DISPLAY 0.638298 (-814 5150);
PAINT MONO (-814 5150);
FORCEPROP 2 LAST CDS_LIB standard
J 0
(-1000 5150);
DISPLAY INVISIBLE (-1000 5150);
FORCEPROP 1 LAST OFFPAGE TRUE
J 2
(-1325 5025);
DISPLAY 0.872340 (-1325 5025);
DISPLAY INVISIBLE (-1325 5025);
FORCEPROP 1 LAST COMMENT_BODY TRUE
J 2
(-1125 5050);
DISPLAY 0.872340 (-1125 5050);
PAINT GREEN (-1125 5050);
DISPLAY INVISIBLE (-1125 5050);
FORCEPROP 2 LAST PATH I37
J 0
(-825 5225);
DISPLAY 0.680851 (-825 5225);
DISPLAY INVISIBLE (-825 5225);
FORCEADD PT5161LRS..2
(-3250 3800);
FORCEPROP 1 LAST LOCATION U6013
J 0
(-3600 5425);
DISPLAY 0.723404 (-3600 5425);
PAINT GREEN (-3600 5425);
FORCEPROP 0 LAST $SEC 2
J 0
(-3600 5575);
DISPLAY 0.680851 (-3600 5575);
PAINT MONO (-3600 5575);
DISPLAY INVISIBLE (-3600 5575);
FORCEPROP 0 LAST CDS_SEC 2
J 0
(-3600 5575);
DISPLAY 0.680851 (-3600 5575);
DISPLAY INVISIBLE (-3600 5575);
FORCEPROP 0 LASTPIN (-2800 4950) $PN CJ2
J 0
(-2790 4960);
DISPLAY 0.680851 (-2790 4960);
PAINT MONO (-2790 4960);
FORCEPROP 0 LASTPIN (-2800 4600) $PN CT2
J 0
(-2790 4610);
DISPLAY 0.680851 (-2790 4610);
PAINT MONO (-2790 4610);
FORCEPROP 0 LASTPIN (-2800 4250) $PN DC2
J 0
(-2790 4260);
DISPLAY 0.680851 (-2790 4260);
PAINT MONO (-2790 4260);
FORCEPROP 0 LASTPIN (-2800 3900) $PN DK2
J 0
(-2790 3910);
DISPLAY 0.680851 (-2790 3910);
PAINT MONO (-2790 3910);
FORCEPROP 0 LASTPIN (-2800 3550) $PN DU2
J 0
(-2790 3560);
DISPLAY 0.680851 (-2790 3560);
PAINT MONO (-2790 3560);
FORCEPROP 0 LASTPIN (-2800 3200) $PN ED2
J 0
(-2790 3210);
DISPLAY 0.680851 (-2790 3210);
PAINT MONO (-2790 3210);
FORCEPROP 0 LASTPIN (-2800 2850) $PN EL2
J 0
(-2790 2860);
DISPLAY 0.680851 (-2790 2860);
PAINT MONO (-2790 2860);
FORCEPROP 0 LASTPIN (-2800 2500) $PN EV2
J 0
(-2790 2510);
DISPLAY 0.680851 (-2790 2510);
PAINT MONO (-2790 2510);
FORCEPROP 0 LASTPIN (-2800 5050) $PN CL1
J 0
(-2790 5060);
DISPLAY 0.680851 (-2790 5060);
PAINT MONO (-2790 5060);
FORCEPROP 0 LASTPIN (-2800 4700) $PN CV1
J 0
(-2790 4710);
DISPLAY 0.680851 (-2790 4710);
PAINT MONO (-2790 4710);
FORCEPROP 0 LASTPIN (-2800 4350) $PN DE1
J 0
(-2790 4360);
DISPLAY 0.680851 (-2790 4360);
PAINT MONO (-2790 4360);
FORCEPROP 0 LASTPIN (-2800 4000) $PN DM1
J 0
(-2790 4010);
DISPLAY 0.680851 (-2790 4010);
PAINT MONO (-2790 4010);
FORCEPROP 0 LASTPIN (-2800 3650) $PN DW1
J 0
(-2790 3660);
DISPLAY 0.680851 (-2790 3660);
PAINT MONO (-2790 3660);
FORCEPROP 0 LASTPIN (-2800 3300) $PN EF1
J 0
(-2790 3310);
DISPLAY 0.680851 (-2790 3310);
PAINT MONO (-2790 3310);
FORCEPROP 0 LASTPIN (-2800 2950) $PN EN1
J 0
(-2790 2960);
DISPLAY 0.680851 (-2790 2960);
PAINT MONO (-2790 2960);
FORCEPROP 0 LASTPIN (-2800 2600) $PN EY1
J 0
(-2790 2610);
DISPLAY 0.680851 (-2790 2610);
PAINT MONO (-2790 2610);
FORCEPROP 2 LAST VALUE PT5161LRS
J 0
(-3600 5475);
DISPLAY 0.680851 (-3600 5475);
FORCEPROP 1 LAST MATERIAL IC
J 0
(-3600 5275);
DISPLAY 0.723404 (-3600 5275);
PAINT GREEN (-3600 5275);
FORCEPROP 2 LAST PART_TYPE SMLF
J 0
(-3600 5525);
DISPLAY 0.680851 (-3600 5525);
FORCEPROP 1 LAST NEEDS_NO_SIZE TRUE
J 0
(-3250 3800);
DISPLAY 0.723404 (-3250 3800);
PAINT GREEN (-3250 3800);
DISPLAY INVISIBLE (-3250 3800);
FORCEPROP 1 LAST CDS_LMAN_SYM_OUTLINE -350,1450,300,-1400
J 0
(-3250 3800);
DISPLAY 0.468085 (-3250 3800);
PAINT GREEN (-3250 3800);
DISPLAY INVISIBLE (-3250 3800);
FORCEPROP 2 LAST CDS_LIB pure_quanta
J 0
(-3250 3800);
DISPLAY INVISIBLE (-3250 3800);
FORCEPROP 1 LAST PATH I38
J 0
(-3250 3800);
DISPLAY 0.723404 (-3250 3800);
PAINT GREEN (-3250 3800);
DISPLAY INVISIBLE (-3250 3800);
FORCEPROP 1 LAST PART_NUMBER AJ051610U03
J 0
(-3600 5350);
DISPLAY 0.723404 (-3600 5350);
PAINT GREEN (-3600 5350);
DISPLAY INVISIBLE (-3600 5350);
FORCEADD TAP..1
(-6675 2925);
FORCEPROP 3 LASTPIN (-6725 2925) SIG_NAME P5E_CPU0_P3_RX_BUF_DP<9>
J 0
(-6715 2935);
DISPLAY 0.659574 (-6715 2935);
PAINT MONO (-6715 2935);
DISPLAY INVISIBLE (-6715 2935);
FORCEPROP 1 LASTPIN (-6725 2925) BN 9
J 0
(-6737 2933);
DISPLAY 0.680851 (-6737 2933);
PAINT GREEN (-6737 2933);
FORCEPROP 2 LAST CDS_LIB standard
J 0
(-6675 2925);
DISPLAY INVISIBLE (-6675 2925);
FORCEPROP 1 LAST BODY_TYPE PLUMBING
J 0
(-6675 2975);
DISPLAY 0.872340 (-6675 2975);
PAINT GREEN (-6675 2975);
DISPLAY INVISIBLE (-6675 2975);
FORCEPROP 1 LAST HDL_TAP TRUE
J 0
(-6350 2800);
DISPLAY 0.872340 (-6350 2800);
DISPLAY INVISIBLE (-6350 2800);
FORCEPROP 1 LAST PATH I4
J 0
(-6677 2925);
DISPLAY 0.872340 (-6677 2925);
PAINT GREEN (-6677 2925);
DISPLAY INVISIBLE (-6677 2925);
FORCEADD TAP..1
(-6475 2825);
FORCEPROP 3 LASTPIN (-6525 2825) SIG_NAME P5E_CPU0_P3_RX_BUF_DN<9>
J 0
(-6515 2835);
DISPLAY 0.659574 (-6515 2835);
PAINT MONO (-6515 2835);
DISPLAY INVISIBLE (-6515 2835);
FORCEPROP 1 LASTPIN (-6525 2825) BN 9
J 0
(-6537 2833);
DISPLAY 0.680851 (-6537 2833);
PAINT GREEN (-6537 2833);
FORCEPROP 2 LAST CDS_LIB standard
J 0
(-6475 2825);
DISPLAY INVISIBLE (-6475 2825);
FORCEPROP 1 LAST BODY_TYPE PLUMBING
J 0
(-6475 2875);
DISPLAY 0.872340 (-6475 2875);
PAINT GREEN (-6475 2875);
DISPLAY INVISIBLE (-6475 2875);
FORCEPROP 1 LAST HDL_TAP TRUE
J 0
(-6150 2700);
DISPLAY 0.872340 (-6150 2700);
DISPLAY INVISIBLE (-6150 2700);
FORCEPROP 1 LAST PATH I5
J 0
(-6477 2825);
DISPLAY 0.872340 (-6477 2825);
PAINT GREEN (-6477 2825);
DISPLAY INVISIBLE (-6477 2825);
FORCEADD TAP..1
(-6675 3275);
FORCEPROP 3 LASTPIN (-6725 3275) SIG_NAME P5E_CPU0_P3_RX_BUF_DP<10>
J 0
(-6715 3285);
DISPLAY 0.659574 (-6715 3285);
PAINT MONO (-6715 3285);
DISPLAY INVISIBLE (-6715 3285);
FORCEPROP 1 LASTPIN (-6725 3275) BN 10
J 0
(-6737 3283);
DISPLAY 0.680851 (-6737 3283);
PAINT GREEN (-6737 3283);
FORCEPROP 2 LAST CDS_LIB standard
J 0
(-6675 3275);
DISPLAY INVISIBLE (-6675 3275);
FORCEPROP 1 LAST BODY_TYPE PLUMBING
J 0
(-6675 3325);
DISPLAY 0.872340 (-6675 3325);
PAINT GREEN (-6675 3325);
DISPLAY INVISIBLE (-6675 3325);
FORCEPROP 1 LAST HDL_TAP TRUE
J 0
(-6350 3150);
DISPLAY 0.872340 (-6350 3150);
DISPLAY INVISIBLE (-6350 3150);
FORCEPROP 1 LAST PATH I6
J 0
(-6677 3275);
DISPLAY 0.872340 (-6677 3275);
PAINT GREEN (-6677 3275);
DISPLAY INVISIBLE (-6677 3275);
FORCEADD TAP..1
(-6475 3175);
FORCEPROP 3 LASTPIN (-6525 3175) SIG_NAME P5E_CPU0_P3_RX_BUF_DN<10>
J 0
(-6515 3185);
DISPLAY 0.659574 (-6515 3185);
PAINT MONO (-6515 3185);
DISPLAY INVISIBLE (-6515 3185);
FORCEPROP 1 LASTPIN (-6525 3175) BN 10
J 0
(-6537 3183);
DISPLAY 0.680851 (-6537 3183);
PAINT GREEN (-6537 3183);
FORCEPROP 2 LAST CDS_LIB standard
J 0
(-6475 3175);
DISPLAY INVISIBLE (-6475 3175);
FORCEPROP 1 LAST BODY_TYPE PLUMBING
J 0
(-6475 3225);
DISPLAY 0.872340 (-6475 3225);
PAINT GREEN (-6475 3225);
DISPLAY INVISIBLE (-6475 3225);
FORCEPROP 1 LAST HDL_TAP TRUE
J 0
(-6150 3050);
DISPLAY 0.872340 (-6150 3050);
DISPLAY INVISIBLE (-6150 3050);
FORCEPROP 1 LAST PATH I7
J 0
(-6477 3175);
DISPLAY 0.872340 (-6477 3175);
PAINT GREEN (-6477 3175);
DISPLAY INVISIBLE (-6477 3175);
FORCEADD TAP..1
(-6475 3525);
FORCEPROP 3 LASTPIN (-6525 3525) SIG_NAME P5E_CPU0_P3_RX_BUF_DN<11>
J 0
(-6515 3535);
DISPLAY 0.659574 (-6515 3535);
PAINT MONO (-6515 3535);
DISPLAY INVISIBLE (-6515 3535);
FORCEPROP 1 LASTPIN (-6525 3525) BN 11
J 0
(-6537 3533);
DISPLAY 0.680851 (-6537 3533);
PAINT GREEN (-6537 3533);
FORCEPROP 2 LAST CDS_LIB standard
J 0
(-6475 3525);
DISPLAY INVISIBLE (-6475 3525);
FORCEPROP 1 LAST BODY_TYPE PLUMBING
J 0
(-6475 3575);
DISPLAY 0.872340 (-6475 3575);
PAINT GREEN (-6475 3575);
DISPLAY INVISIBLE (-6475 3575);
FORCEPROP 1 LAST HDL_TAP TRUE
J 0
(-6150 3400);
DISPLAY 0.872340 (-6150 3400);
DISPLAY INVISIBLE (-6150 3400);
FORCEPROP 1 LAST PATH I8
J 0
(-6477 3525);
DISPLAY 0.872340 (-6477 3525);
PAINT GREEN (-6477 3525);
DISPLAY INVISIBLE (-6477 3525);
FORCEADD TAP..1
(-6675 3625);
FORCEPROP 3 LASTPIN (-6725 3625) SIG_NAME P5E_CPU0_P3_RX_BUF_DP<11>
J 0
(-6715 3635);
DISPLAY 0.659574 (-6715 3635);
PAINT MONO (-6715 3635);
DISPLAY INVISIBLE (-6715 3635);
FORCEPROP 1 LASTPIN (-6725 3625) BN 11
J 0
(-6737 3633);
DISPLAY 0.680851 (-6737 3633);
PAINT GREEN (-6737 3633);
FORCEPROP 2 LAST CDS_LIB standard
J 0
(-6675 3625);
DISPLAY INVISIBLE (-6675 3625);
FORCEPROP 1 LAST BODY_TYPE PLUMBING
J 0
(-6675 3675);
DISPLAY 0.872340 (-6675 3675);
PAINT GREEN (-6675 3675);
DISPLAY INVISIBLE (-6675 3675);
FORCEPROP 1 LAST HDL_TAP TRUE
J 0
(-6350 3500);
DISPLAY 0.872340 (-6350 3500);
DISPLAY INVISIBLE (-6350 3500);
FORCEPROP 1 LAST PATH I9
J 0
(-6677 3625);
DISPLAY 0.872340 (-6677 3625);
PAINT GREEN (-6677 3625);
DISPLAY INVISIBLE (-6677 3625);
FORCEADD QUANTA_TITLE_BLOCK_C..1
(0 0);
FORCEPROP 0 LAST CDS_CON_LAST_MODIFIED Thu Sep 14 16:12:53 2023
J 0
(-1885 15);
DISPLAY INVISIBLE (-1885 15);
FORCEPROP 1 LAST CUSTOM_TXT_CDS <CON_LAST_MODIFIED>
J 0
(-1885 15);
DISPLAY 0.978723 (-1885 15);
FORCEPROP 2 LAST CUSTOM_TXT_CDS <XR_PAGE_TITLE>
J 0
(-7890 5250);
DISPLAY 0.638298 (-7890 5250);
PAINT PINK (-7890 5250);
DISPLAY INVISIBLE (-7890 5250);
FORCEPROP 1 LAST CUSTOM_TXT_CDS <NAME_2>
J 0
(-3175 50);
FORCEPROP 1 LAST CUSTOM_TXT_CDS <NAME_1>
J 0
(-3175 175);
FORCEPROP 1 LAST CUSTOM_TXT_CDS <Q_NUMBER>
J 0
(-1403 103);
DISPLAY 1.212766 (-1403 103);
FORCEPROP 1 LAST CUSTOM_TXT_CDS <Q_PROJ>
J 0
(-2382 102);
DISPLAY 1.212766 (-2382 102);
FORCEPROP 1 LAST CUSTOM_TXT_CDS <Q_REV>
J 0
(-184 103);
DISPLAY 1.212766 (-184 103);
FORCEPROP 1 LAST CUSTOM_TXT_CDS <CON_PAGE_NUM> OF <CON_TOTAL_PAGES>
J 0
(-446 18);
DISPLAY 0.978723 (-446 18);
FORCEPROP 1 LAST Q_TITLE RETIMER_CPU0_P3(3)
J 0
(-9366 26);
DISPLAY 2.446809 (-9366 26);
PAINT GREEN (-9366 26);
FORCEPROP 2 LAST PAGE_BORDER TRUE
J 0
(-7890 5250);
DISPLAY 0.638298 (-7890 5250);
PAINT PINK (-7890 5250);
DISPLAY INVISIBLE (-7890 5250);
FORCEPROP 1 LAST CDS_LMAN_SYM_OUTLINE -9475,6775,100,-125
J 0
(0 0);
DISPLAY 0.468085 (0 0);
PAINT GREEN (0 0);
DISPLAY INVISIBLE (0 0);
FORCEPROP 2 LAST CDS_LIB pure_quanta
J 0
(0 0);
DISPLAY INVISIBLE (0 0);
FORCEPROP 2 LAST CDS_XR_PAGE_TITLE CR-308 : @T6G_MB_LIB.T6G(SCH_1):PAGE308
J 0
(-7890 5250);
DISPLAY 0.638298 (-7890 5250);
PAINT PINK (-7890 5250);
DISPLAY INVISIBLE (-7890 5250);
FORCEPROP 1 LAST Q_DEPT BU9
J 1
(-3763 49);
DISPLAY 1.957447 (-3763 49);
PAINT GREEN (-3763 49);
DISPLAY INVISIBLE (-3763 49);
FORCEPROP 1 LAST COMMENT_BODY TRUE
J 0
(12 -13);
DISPLAY 0.978723 (12 -13);
PAINT GREEN (12 -13);
DISPLAY INVISIBLE (12 -13);
WIRE 17 -1 (-6625 5125)(-6625 5050);
WIRE 17 -1 (-6625 5125)(-5500 5125);
FORCEPROP 2 LAST SIG_NAME P5E_CPU0_P3_RX_BUF_DP<15:8>
J 0
(-6360 5135);
DISPLAY 0.680851 (-6360 5135);
PAINT WHITE (-6360 5135);
WIRE 17 -1 (-1975 3225)(-1975 2875);
WIRE 17 -1 (-1975 3575)(-1975 3225);
WIRE 17 -1 (-1975 2875)(-1975 2525);
WIRE 17 -1 (-1975 3575)(-1975 3925);
WIRE 17 -1 (-1975 4275)(-1975 3925);
WIRE 17 -1 (-1975 4625)(-1975 4275);
WIRE 17 -1 (-1975 4975)(-1975 4625);
WIRE 17 -1 (-1975 5075)(-1975 4975);
WIRE 17 -1 (-1975 5075)(-1050 5075);
FORCEPROP 2 LAST SIG_NAME P5E_CPU0_P3_RX_BUF_DN<7:0>
J 0
(-1910 5085);
DISPLAY 0.680851 (-1910 5085);
PAINT WHITE (-1910 5085);
WIRE 17 -1 (-2175 3325)(-2175 2975);
WIRE 17 -1 (-2175 3675)(-2175 3325);
WIRE 17 -1 (-2175 2975)(-2175 2625);
WIRE 17 -1 (-2175 3675)(-2175 4025);
WIRE 17 -1 (-2175 4375)(-2175 4025);
WIRE 17 -1 (-2175 4725)(-2175 4375);
WIRE 17 -1 (-2175 5075)(-2175 4725);
WIRE 17 -1 (-2175 5150)(-2175 5075);
WIRE 17 -1 (-2175 5150)(-1050 5150);
FORCEPROP 2 LAST SIG_NAME P5E_CPU0_P3_RX_BUF_DP<7:0>
J 0
(-1910 5160);
DISPLAY 0.680851 (-1910 5160);
PAINT WHITE (-1910 5160);
WIRE 17 -1 (-6425 4950)(-6425 4600);
WIRE 17 -1 (-6425 5050)(-6425 4950);
WIRE 17 -1 (-6425 4600)(-6425 4250);
WIRE 17 -1 (-6425 4250)(-6425 3900);
WIRE 17 -1 (-6425 5050)(-5500 5050);
FORCEPROP 2 LAST SIG_NAME P5E_CPU0_P3_RX_BUF_DN<15:8>
J 0
(-6360 5060);
DISPLAY 0.680851 (-6360 5060);
PAINT WHITE (-6360 5060);
WIRE 17 -1 (-6625 5050)(-6625 4700);
WIRE 17 -1 (-6625 4700)(-6625 4350);
WIRE 17 -1 (-6625 4350)(-6625 4000);
WIRE 17 -1 (-6425 3550)(-6425 3900);
WIRE 17 -1 (-6425 3550)(-6425 3200);
WIRE 17 -1 (-6425 3200)(-6425 2850);
WIRE 17 -1 (-6425 2850)(-6425 2500);
WIRE 17 -1 (-6625 2950)(-6625 2600);
WIRE 17 -1 (-6625 3300)(-6625 2950);
WIRE 17 -1 (-6625 3650)(-6625 3300);
WIRE 17 -1 (-6625 3650)(-6625 4000);
WIRE 16 -1 (-7250 2925)(-6725 2925);
WIRE 16 -1 (-2800 4700)(-2275 4700);
WIRE 16 -1 (-2800 4600)(-2075 4600);
WIRE 16 -1 (-2800 3650)(-2275 3650);
WIRE 16 -1 (-2800 4350)(-2275 4350);
WIRE 16 -1 (-2800 5050)(-2275 5050);
WIRE 16 -1 (-7250 3625)(-6725 3625);
WIRE 16 -1 (-7250 3275)(-6725 3275);
WIRE 16 -1 (-7250 3975)(-6725 3975);
WIRE 16 -1 (-7250 2475)(-6525 2475);
WIRE 16 -1 (-7250 3875)(-6525 3875);
WIRE 16 -1 (-7250 4325)(-6725 4325);
WIRE 16 -1 (-7250 2575)(-6725 2575);
WIRE 16 -1 (-7250 2825)(-6525 2825);
WIRE 16 -1 (-7250 3175)(-6525 3175);
WIRE 16 -1 (-7250 3525)(-6525 3525);
WIRE 16 -1 (-7250 4225)(-6525 4225);
WIRE 16 -1 (-7250 4675)(-6725 4675);
WIRE 16 -1 (-2800 2600)(-2275 2600);
WIRE 16 -1 (-2800 2500)(-2075 2500);
WIRE 16 -1 (-2800 3900)(-2075 3900);
WIRE 16 -1 (-7250 4925)(-6525 4925);
WIRE 16 -1 (-7250 4575)(-6525 4575);
WIRE 16 -1 (-2800 4000)(-2275 4000);
WIRE 16 -1 (-2800 4250)(-2075 4250);
WIRE 16 -1 (-2800 4950)(-2075 4950);
WIRE 16 -1 (-2800 3550)(-2075 3550);
WIRE 16 -1 (-2800 3300)(-2275 3300);
WIRE 16 -1 (-2800 3200)(-2075 3200);
WIRE 16 -1 (-2800 2950)(-2275 2950);
WIRE 16 -1 (-2800 2850)(-2075 2850);
WIRE 16 -1 (-7250 5025)(-6725 5025);
FORCENOTE
P5E_CPU0_P3_RX_BUF_DP/DN<0-15> LANE REVERSAL
(-9125 6250) 0;
DISPLAY LEFT (-9125 6250);
DISPLAY 2.000000 (-9125 6250);
FORCENOTE
EXAMAX TO RETIMER
(-8075 1650) 0;
DISPLAY LEFT (-8075 1650);
DISPLAY 3.148936 (-8075 1650);
FORCENOTE
EXAMAX TO RETIMER
(-3525 1625) 0;
DISPLAY LEFT (-3525 1625);
DISPLAY 3.148936 (-3525 1625);
QUIT
